# SCM (Grand Teton) — schematic netlist excerpt (pin names and nets, part order shuffled) for the footprints in the layout excerpt that follows; sources: Cadence DE-HDL packaged netlist, KiCad conversion of 12092022_DA0F0TMDCD0_F0T_Management_Board_D_brd_V3_OCP.brd

R50  Q_RES  10K 1% CHIP  pkg 0402LF  page 46 : A = P3V3_AUX ; B = FM_TPM_PRSNT_1_N
PR532  Q_RES  60.4K 1% CHIP  pkg 0402LF  page 52 : A = GND ; B = P3V3_AUX_MODE

(kicad_pcb
	(version 20260206)
	(generator "pcbnew")
	(generator_version "10.0")
	(general
		(thickness 1.6)
		(legacy_teardrops no)
	)
	(paper "A4")
	(title_block
		(title "12092022_DA0F0TMDCD0_F0T_Management_Board_D_brd_V3_OCP.brd")
		(comment 1 "Grand Teton / footprints 51-53 of 1440")
	)
	(layers
		(0 "F.Cu" signal "TOP")
		(4 "In1.Cu" signal "GND")
		(6 "In2.Cu" signal "IN1")
		(8 "In3.Cu" signal "GND1")
		(10 "In4.Cu" signal "IN2")
		(12 "In5.Cu" signal "VCC")
		(14 "In6.Cu" signal "VCC1")
		(16 "In7.Cu" signal "IN3")
		(18 "In8.Cu" signal "GND2")
		(20 "In9.Cu" signal "IN4")
		(22 "In10.Cu" signal "GND3")
		(2 "B.Cu" signal "BOTTOM")
		(9 "F.Adhes" user "F.Adhesive")
		(11 "B.Adhes" user "B.Adhesive")
		(13 "F.Paste" user "Package Geometry/Pastemask Top")
		(15 "B.Paste" user "Package Geometry/Pastemask Bottom")
		(5 "F.SilkS" user "Ref Des/Silkscreen Top")
		(7 "B.SilkS" user "Ref Des/Silkscreen Bottom")
		(1 "F.Mask" user "Board Geometry/Soldermask Top")
		(3 "B.Mask" user "Board Geometry/Soldermask Bottom")
		(17 "Dwgs.User" user "User.Drawings")
		(19 "Cmts.User" user "User.Comments")
		(21 "Eco1.User" user "User.Eco1")
		(23 "Eco2.User" user "User.Eco2")
		(25 "Edge.Cuts" user "Board Geometry/Outline")
		(27 "Margin" user)
		(31 "F.CrtYd" user "Package Geometry/Place Bound Top")
		(29 "B.CrtYd" user "Package Geometry/Place Bound Bottom")
		(35 "F.Fab" user "Ref Des/Assembly Top")
		(33 "B.Fab" user "Ref Des/Assembly Bottom")
	)
	(footprint ""
		(layer "F.Cu")
		(at 5.01015 -65.983358)
		(property "Reference" "PR532"
			(at 0 0 0)
			(layer "F.SilkS")
			(hide yes)
			(effects
				(font
					(size 1.27 1.27)
				)
			)
		)
		(property "Value" ""
			(at 0 0 0)
			(layer "F.Fab")
			(effects
				(font
					(size 1.27 1.27)
				)
			)
		)
		(duplicate_pad_numbers_are_jumpers no)
		(fp_line
			(start -0.7874 -0.4064)
			(end 0.7874 -0.4064)
			(stroke
				(width 0.1524)
				(type default)
			)
			(layer "F.SilkS")
		)
		(fp_line
			(start -0.7874 0.4064)
			(end -0.7874 -0.4064)
			(stroke
				(width 0.1524)
				(type default)
			)
			(layer "F.SilkS")
		)
		(fp_line
			(start 0.7874 -0.4064)
			(end 0.7874 0.4064)
			(stroke
				(width 0.1524)
				(type default)
			)
			(layer "F.SilkS")
		)
		(fp_line
			(start 0.7874 0.4064)
			(end -0.7874 0.4064)
			(stroke
				(width 0.1524)
				(type default)
			)
			(layer "F.SilkS")
		)
		(fp_line
			(start -0.67945 -0.305054)
			(end -0.12065 -0.305054)
			(stroke
				(width 0.1)
				(type default)
			)
			(layer "F.Fab")
		)
		(fp_line
			(start -0.67945 0.3048)
			(end -0.67945 -0.305054)
			(stroke
				(width 0.1)
				(type default)
			)
			(layer "F.Fab")
		)
		(fp_line
			(start -0.12065 -0.305054)
			(end -0.12065 -0.2794)
			(stroke
				(width 0.1)
				(type default)
			)
			(layer "F.Fab")
		)
		(fp_line
			(start -0.12065 -0.2794)
			(end 0.12065 -0.2794)
			(stroke
				(width 0.1)
				(type default)
			)
			(layer "F.Fab")
		)
		(fp_line
			(start -0.12065 0.2794)
			(end -0.12065 0.3048)
			(stroke
				(width 0.1)
				(type default)
			)
			(layer "F.Fab")
		)
		(fp_line
			(start -0.12065 0.3048)
			(end -0.67945 0.3048)
			(stroke
				(width 0.1)
				(type default)
			)
			(layer "F.Fab")
		)
		(fp_line
			(start 0.120396 0.2794)
			(end -0.12065 0.2794)
			(stroke
				(width 0.1)
				(type default)
			)
			(layer "F.Fab")
		)
		(fp_line
			(start 0.120396 0.3048)
			(end 0.120396 0.2794)
			(stroke
				(width 0.1)
				(type default)
			)
			(layer "F.Fab")
		)
		(fp_line
			(start 0.12065 -0.3048)
			(end 0.67945 -0.3048)
			(stroke
				(width 0.1)
				(type default)
			)
			(layer "F.Fab")
		)
		(fp_line
			(start 0.12065 -0.2794)
			(end 0.12065 -0.3048)
			(stroke
				(width 0.1)
				(type default)
			)
			(layer "F.Fab")
		)
		(fp_line
			(start 0.67945 -0.3048)
			(end 0.67945 0.3048)
			(stroke
				(width 0.1)
				(type default)
			)
			(layer "F.Fab")
		)
		(fp_line
			(start 0.67945 0.3048)
			(end 0.120396 0.3048)
			(stroke
				(width 0.1)
				(type default)
			)
			(layer "F.Fab")
		)
		(pad "1" smd circle
			(at -0.40005 0)
			(size 0 0)
			(layers "F.Cu" "F.Mask" "F.Paste")
			(net "GND")
		)
		(pad "2" smd circle
			(at 0.40005 0)
			(size 0 0)
			(layers "F.Cu" "F.Mask" "F.Paste")
			(net "P3V3_AUX_MODE")
		)
	)
	(footprint ""
		(layer "F.Cu")
		(at 74.09815 -93.347032)
		(property "Reference" "R50"
			(at 0 0 0)
			(layer "F.SilkS")
			(hide yes)
			(effects
				(font
					(size 1.27 1.27)
				)
			)
		)
		(property "Value" ""
			(at 0 0 0)
			(layer "F.Fab")
			(effects
				(font
					(size 1.27 1.27)
				)
			)
		)
		(duplicate_pad_numbers_are_jumpers no)
		(fp_line
			(start -0.7874 -0.4064)
			(end 0.7874 -0.4064)
			(stroke
				(width 0.1524)
				(type default)
			)
			(layer "F.SilkS")
		)
		(fp_line
			(start -0.7874 0.4064)
			(end -0.7874 -0.4064)
			(stroke
				(width 0.1524)
				(type default)
			)
			(layer "F.SilkS")
		)
		(fp_line
			(start 0.7874 -0.4064)
			(end 0.7874 0.4064)
			(stroke
				(width 0.1524)
				(type default)
			)
			(layer "F.SilkS")
		)
		(fp_line
			(start 0.7874 0.4064)
			(end -0.7874 0.4064)
			(stroke
				(width 0.1524)
				(type default)
			)
			(layer "F.SilkS")
		)
		(fp_line
			(start -0.67945 -0.305054)
			(end -0.12065 -0.305054)
			(stroke
				(width 0.1)
				(type default)
			)
			(layer "F.Fab")
		)
		(fp_line
			(start -0.67945 0.3048)
			(end -0.67945 -0.305054)
			(stroke
				(width 0.1)
				(type default)
			)
			(layer "F.Fab")
		)
		(fp_line
			(start -0.12065 -0.305054)
			(end -0.12065 -0.2794)
			(stroke
				(width 0.1)
				(type default)
			)
			(layer "F.Fab")
		)
		(fp_line
			(start -0.12065 -0.2794)
			(end 0.12065 -0.2794)
			(stroke
				(width 0.1)
				(type default)
			)
			(layer "F.Fab")
		)
		(fp_line
			(start -0.12065 0.2794)
			(end -0.12065 0.3048)
			(stroke
				(width 0.1)
				(type default)
			)
			(layer "F.Fab")
		)
		(fp_line
			(start -0.12065 0.3048)
			(end -0.67945 0.3048)
			(stroke
				(width 0.1)
				(type default)
			)
			(layer "F.Fab")
		)
		(fp_line
			(start 0.120396 0.2794)
			(end -0.12065 0.2794)
			(stroke
				(width 0.1)
				(type default)
			)
			(layer "F.Fab")
		)
		(fp_line
			(start 0.120396 0.3048)
			(end 0.120396 0.2794)
			(stroke
				(width 0.1)
				(type default)
			)
			(layer "F.Fab")
		)
		(fp_line
			(start 0.12065 -0.3048)
			(end 0.67945 -0.3048)
			(stroke
				(width 0.1)
				(type default)
			)
			(layer "F.Fab")
		)
		(fp_line
			(start 0.12065 -0.2794)
			(end 0.12065 -0.3048)
			(stroke
				(width 0.1)
				(type default)
			)
			(layer "F.Fab")
		)
		(fp_line
			(start 0.67945 -0.3048)
			(end 0.67945 0.3048)
			(stroke
				(width 0.1)
				(type default)
			)
			(layer "F.Fab")
		)
		(fp_line
			(start 0.67945 0.3048)
			(end 0.120396 0.3048)
			(stroke
				(width 0.1)
				(type default)
			)
			(layer "F.Fab")
		)
		(pad "1" smd circle
			(at -0.40005 0)
			(size 0 0)
			(layers "F.Cu" "F.Mask" "F.Paste")
			(net "P3V3_AUX")
		)
		(pad "2" smd circle
			(at 0.40005 0)
			(size 0 0)
			(layers "F.Cu" "F.Mask" "F.Paste")
			(net "FM_TPM_PRSNT_1_N")
		)
	)
	(footprint ""
		(layer "F.Cu")
		(at 68.4784 -85.7758)
		(property "Reference" ""
			(at 0 0 0)
			(layer "F.SilkS")
			(hide yes)
			(effects
				(font
					(size 1.27 1.27)
				)
			)
		)
		(property "Value" ""
			(at 0 0 0)
			(layer "F.Fab")
			(effects
				(font
					(size 1.27 1.27)
				)
			)
		)
		(duplicate_pad_numbers_are_jumpers no)
		(pad "1" smd circle
			(at 0 0)
			(size 0.9906 0.9906)
			(layers "F.Cu" "F.Mask" "F.Paste")
			(net "Net_327")
		)
		(zone
			(layer "F.Cu")
			(hatch none 0.5)
			(connect_pads
				(clearance 0)
			)
			(min_thickness 0.25)
			(keepout
				(tracks not_allowed)
				(vias allowed)
				(pads allowed)
				(copperpour not_allowed)
				(footprints allowed)
			)
			(placement
				(enabled no)
				(sheetname "")
			)
			(fill
				(thermal_gap 0.5)
				(thermal_bridge_width 0.5)
				(island_removal_mode 0)
			)
			(polygon
				(pts
					(arc
						(start 70.104 -85.7758)
						(mid 66.8528 -85.7758)
						(end 70.104 -85.7758)
					)
				)
			)
		)
	)
)
